# T6G (Grand Teton) — schematic netlist excerpt (pin names and nets, part order shuffled) for the footprints in the layout excerpt that follows; sources: Cadence DE-HDL packaged netlist, KiCad conversion of 04192023_DAF0TMB3IC0_F0TG_MB_C_brd_V02_OCP.brd

C532  Q_CAP  10UF 25V 10% X6S  pkg C0805  page 105 : A = P12V_MEM_CPU1 ; B = GND
C648  Q_CAP  10UF 6.3V 20% X6S  pkg C0402  page 290 : A = P0V9_CPU0_RT1_2A ; B = GND

(kicad_pcb
	(version 20260206)
	(generator "pcbnew")
	(generator_version "10.0")
	(general
		(thickness 1.6)
		(legacy_teardrops no)
	)
	(paper "A4")
	(title_block
		(title "04192023_DAF0TMB3IC0_F0TG_MB_C_brd_V02_OCP.brd")
		(comment 1 "Grand Teton / footprints 6173-6174 of 8354")
	)
	(layers
		(0 "F.Cu" signal "TOP")
		(4 "In1.Cu" signal "GND")
		(6 "In2.Cu" signal "IN1")
		(8 "In3.Cu" signal "GND1")
		(10 "In4.Cu" signal "IN2")
		(12 "In5.Cu" signal "GND2")
		(14 "In6.Cu" signal "IN3")
		(16 "In7.Cu" signal "GND3")
		(18 "In8.Cu" signal "VCC")
		(20 "In9.Cu" signal "VCC1")
		(22 "In10.Cu" signal "GND4")
		(24 "In11.Cu" signal "IN4")
		(26 "In12.Cu" signal "GND5")
		(28 "In13.Cu" signal "IN5")
		(30 "In14.Cu" signal "GND6")
		(32 "In15.Cu" signal "IN6")
		(34 "In16.Cu" signal "GND7")
		(2 "B.Cu" signal "BOTTOM")
		(9 "F.Adhes" user "F.Adhesive")
		(11 "B.Adhes" user "B.Adhesive")
		(13 "F.Paste" user "Package Geometry/Pastemask Top")
		(15 "B.Paste" user "Package Geometry/Pastemask Bottom")
		(5 "F.SilkS" user "Ref Des/Silkscreen Top")
		(7 "B.SilkS" user "Ref Des/Silkscreen Bottom")
		(1 "F.Mask" user "Board Geometry/Soldermask Top")
		(3 "B.Mask" user "Board Geometry/Soldermask Bottom")
		(17 "Dwgs.User" user "User.Drawings")
		(19 "Cmts.User" user "User.Comments")
		(21 "Eco1.User" user "User.Eco1")
		(23 "Eco2.User" user "User.Eco2")
		(25 "Edge.Cuts" user "Board Geometry/Outline")
		(27 "Margin" user)
		(31 "F.CrtYd" user "Package Geometry/Place Bound Top")
		(29 "B.CrtYd" user "Package Geometry/Place Bound Bottom")
		(35 "F.Fab" user "Ref Des/Assembly Top")
		(33 "B.Fab" user "Ref Des/Assembly Bottom")
	)
	(footprint ""
		(layer "B.Cu")
		(at 350.318832 -398.942052 90)
		(property "Reference" "C648"
			(at 0 0 90)
			(layer "B.SilkS")
			(hide yes)
			(effects
				(font
					(size 1.27 1.27)
				)
				(justify mirror)
			)
		)
		(property "Value" ""
			(at 0 0 90)
			(layer "B.Fab")
			(effects
				(font
					(size 1.27 1.27)
				)
				(justify mirror)
			)
		)
		(duplicate_pad_numbers_are_jumpers no)
		(fp_line
			(start 0.7874 -0.4064)
			(end -0.7874 -0.4064)
			(stroke
				(width 0.1524)
				(type default)
			)
			(layer "B.SilkS")
		)
		(fp_line
			(start -0.7874 -0.4064)
			(end -0.7874 0.4064)
			(stroke
				(width 0.1524)
				(type default)
			)
			(layer "B.SilkS")
		)
		(fp_line
			(start 0.7874 0.4064)
			(end 0.7874 -0.4064)
			(stroke
				(width 0.1524)
				(type default)
			)
			(layer "B.SilkS")
		)
		(fp_line
			(start -0.7874 0.4064)
			(end 0.7874 0.4064)
			(stroke
				(width 0.1524)
				(type default)
			)
			(layer "B.SilkS")
		)
		(fp_line
			(start 0.67945 -0.305054)
			(end 0.12065 -0.305054)
			(stroke
				(width 0.1)
				(type default)
			)
			(layer "B.Fab")
		)
		(fp_line
			(start 0.12065 -0.305054)
			(end 0.12065 -0.2794)
			(stroke
				(width 0.1)
				(type default)
			)
			(layer "B.Fab")
		)
		(fp_line
			(start -0.12065 -0.3048)
			(end -0.67945 -0.3048)
			(stroke
				(width 0.1)
				(type default)
			)
			(layer "B.Fab")
		)
		(fp_line
			(start -0.67945 -0.3048)
			(end -0.67945 0.3048)
			(stroke
				(width 0.1)
				(type default)
			)
			(layer "B.Fab")
		)
		(fp_line
			(start 0.12065 -0.2794)
			(end -0.12065 -0.2794)
			(stroke
				(width 0.1)
				(type default)
			)
			(layer "B.Fab")
		)
		(fp_line
			(start -0.12065 -0.2794)
			(end -0.12065 -0.3048)
			(stroke
				(width 0.1)
				(type default)
			)
			(layer "B.Fab")
		)
		(fp_line
			(start 0.12065 0.2794)
			(end 0.12065 0.3048)
			(stroke
				(width 0.1)
				(type default)
			)
			(layer "B.Fab")
		)
		(fp_line
			(start -0.120396 0.2794)
			(end 0.12065 0.2794)
			(stroke
				(width 0.1)
				(type default)
			)
			(layer "B.Fab")
		)
		(fp_line
			(start 0.67945 0.3048)
			(end 0.67945 -0.305054)
			(stroke
				(width 0.1)
				(type default)
			)
			(layer "B.Fab")
		)
		(fp_line
			(start 0.12065 0.3048)
			(end 0.67945 0.3048)
			(stroke
				(width 0.1)
				(type default)
			)
			(layer "B.Fab")
		)
		(fp_line
			(start -0.120396 0.3048)
			(end -0.120396 0.2794)
			(stroke
				(width 0.1)
				(type default)
			)
			(layer "B.Fab")
		)
		(fp_line
			(start -0.67945 0.3048)
			(end -0.120396 0.3048)
			(stroke
				(width 0.1)
				(type default)
			)
			(layer "B.Fab")
		)
		(pad "1" smd circle
			(at 0.40005 0 270)
			(size 0 0)
			(layers "B.Cu" "B.Mask" "B.Paste")
			(net "P0V9_CPU0_RT1_2A")
		)
		(pad "2" smd circle
			(at -0.40005 0 270)
			(size 0 0)
			(layers "B.Cu" "B.Mask" "B.Paste")
			(net "GND")
		)
	)
	(footprint ""
		(layer "B.Cu")
		(at 171.972224 -192.66027 180)
		(property "Reference" "C532"
			(at 0 0 0)
			(layer "B.SilkS")
			(hide yes)
			(effects
				(font
					(size 1.27 1.27)
				)
				(justify mirror)
			)
		)
		(property "Value" ""
			(at 0 0 0)
			(layer "B.Fab")
			(effects
				(font
					(size 1.27 1.27)
				)
				(justify mirror)
			)
		)
		(duplicate_pad_numbers_are_jumpers no)
		(fp_line
			(start 1.524 0.762)
			(end 1.524 -0.762)
			(stroke
				(width 0.1524)
				(type default)
			)
			(layer "B.SilkS")
		)
		(fp_line
			(start 1.524 -0.762)
			(end -1.524 -0.762)
			(stroke
				(width 0.1524)
				(type default)
			)
			(layer "B.SilkS")
		)
		(fp_line
			(start -1.524 0.762)
			(end 1.524 0.762)
			(stroke
				(width 0.1524)
				(type default)
			)
			(layer "B.SilkS")
		)
		(fp_line
			(start -1.524 -0.762)
			(end -1.524 0.762)
			(stroke
				(width 0.1524)
				(type default)
			)
			(layer "B.SilkS")
		)
		(fp_line
			(start 1.1049 0.724916)
			(end -1.1049 0.724916)
			(stroke
				(width 0.1)
				(type default)
			)
			(layer "B.Fab")
		)
		(fp_line
			(start 1.1049 -0.724916)
			(end 1.1049 0.724916)
			(stroke
				(width 0.1)
				(type default)
			)
			(layer "B.Fab")
		)
		(fp_line
			(start -1.1049 0.724916)
			(end -1.1049 -0.724916)
			(stroke
				(width 0.1)
				(type default)
			)
			(layer "B.Fab")
		)
		(fp_line
			(start -1.1049 -0.724916)
			(end 1.1049 -0.724916)
			(stroke
				(width 0.1)
				(type default)
			)
			(layer "B.Fab")
		)
		(pad "1" smd rect
			(at 0.889 0 180)
			(size 1.016 1.27)
			(layers "B.Cu" "B.Mask" "B.Paste")
			(net "P12V_MEM_CPU1")
		)
		(pad "2" smd rect
			(at -0.889 0 180)
			(size 1.016 1.27)
			(layers "B.Cu" "B.Mask" "B.Paste")
			(net "GND")
		)
	)
)
